FILE_TYPE = MACRO_DRAWING;
SET COLOR_WIRE YELLOW;
SET COLOR_PROP MONO;
SET COLOR_DOT WHITE;
SET COLOR_ARC YELLOW;
SET COLOR_BODY GREEN;
SET COLOR_NOTE MONO;
SET PROP_DISPLAY VALUE;
SET PAGE_NUMBER P89;
FORCEADD RES..1
(-1650 2400);
FORCEPROP 1 LAST WATTAGE 1/16W
J 2
(-1675 2250);
DISPLAY 0.617021 (-1675 2250);
PAINT SKYBLUE (-1675 2250);
FORCEPROP 1 LAST TOLERANCE 5%
J 0
(-1650 2300);
DISPLAY 0.617021 (-1650 2300);
PAINT SKYBLUE (-1650 2300);
FORCEPROP 1 LAST VALUE 0.0
J 2
(-1675 2300);
DISPLAY 0.617021 (-1675 2300);
PAINT SKYBLUE (-1675 2300);
FORCEPROP 1 LASTPIN (-1750 2400) $PN 1
J 0
(-1738 2412);
DISPLAY 0.617021 (-1738 2412);
PAINT ORANGE (-1738 2412);
FORCEPROP 1 LAST LOCATION R4T2
J 0
(-1700 2450);
DISPLAY 0.617021 (-1700 2450);
PAINT AQUA (-1700 2450);
FORCEPROP 1 LASTPIN (-1550 2400) $PN 2
J 0
(-1588 2412);
DISPLAY 0.617021 (-1588 2412);
PAINT ORANGE (-1588 2412);
FORCEPROP 1 LAST PART_NUMBER G21497-005
J 0
(-1700 2500);
DISPLAY 0.617021 (-1700 2500);
PAINT BLUE (-1700 2500);
FORCEPROP 1 LAST MATERIAL EMPTY
J 0
(-1650 2250);
DISPLAY 0.617021 (-1650 2250);
PAINT RED (-1650 2250);
FORCEPROP 1 LAST PACK_TYPE 0402
J 0
(-1400 2250);
DISPLAY 0.617021 (-1400 2250);
PAINT SKYBLUE (-1400 2250);
FORCEPROP 2 LAST CDS_LOCATION R4T2
J 0
(-1700 2450);
DISPLAY 0.617021 (-1700 2450);
PAINT AQUA (-1700 2450);
DISPLAY INVISIBLE (-1700 2450);
FORCEPROP 2 LAST CDS_LIB mstr_discrete
J 0
(-1650 2400);
PAINT ORANGE (-1650 2400);
DISPLAY INVISIBLE (-1650 2400);
FORCEPROP 1 LAST PATH I1
J 0
(-1700 2550);
DISPLAY 0.978723 (-1700 2550);
PAINT WHITE (-1700 2550);
DISPLAY INVISIBLE (-1700 2550);
FORCEPROP 0 LAST SEC 1
J 0
(-1700 2550);
DISPLAY 0.680851 (-1700 2550);
PAINT MONO (-1700 2550);
DISPLAY INVISIBLE (-1700 2550);
FORCEPROP 0 LAST ROOM NV_DIMM
J 0
(-1700 2600);
DISPLAY 1.021277 (-1700 2600);
PAINT ORANGE (-1700 2600);
DISPLAY INVISIBLE (-1700 2600);
FORCEPROP 2 LAST SEC_TYPE 0402
J 0
(-1700 2600);
DISPLAY 1.021277 (-1700 2600);
PAINT ORANGE (-1700 2600);
DISPLAY INVISIBLE (-1700 2600);
FORCEPROP 0 LAST BOM_COST MEM_NV
J 0
(-1700 2700);
DISPLAY 1.021277 (-1700 2700);
PAINT ORANGE (-1700 2700);
DISPLAY INVISIBLE (-1700 2700);
FORCEADD OFFPAGE..1
(-2650 2100);
FORCEPROP 2 LAST $XR0 191 
J 0
(-2902 2100);
DISPLAY 0.638298 (-2902 2100);
PAINT MONO (-2902 2100);
FORCEPROP 2 LASTPIN (-2600 2100) SIG_NAME FM_ADR_COMPLETE_DLY
J 0
(-2610 2110);
DISPLAY 0.617021 (-2610 2110);
PAINT ORANGE (-2610 2110);
FORCEPROP 1 LAST COMMENT_BODY TRUE
J 0
(-2525 2000);
DISPLAY 0.872340 (-2525 2000);
PAINT GREEN (-2525 2000);
DISPLAY INVISIBLE (-2525 2000);
FORCEPROP 1 LAST OFFPAGE TRUE
J 0
(-2325 1975);
DISPLAY 0.872340 (-2325 1975);
PAINT GREEN (-2325 1975);
DISPLAY INVISIBLE (-2325 1975);
FORCEPROP 2 LAST PATH I10
J 0
(-2600 2175);
DISPLAY 1.021277 (-2600 2175);
PAINT ORANGE (-2600 2175);
DISPLAY INVISIBLE (-2600 2175);
FORCEPROP 2 LAST CDS_LIB mstr_standard
J 0
(-2650 2100);
PAINT ORANGE (-2650 2100);
DISPLAY INVISIBLE (-2650 2100);
FORCEADD OFFPAGE..2
(1500 2500);
FORCEPROP 2 LAST $XR0 43 
J 0
(1689 2500);
DISPLAY 0.638298 (1689 2500);
PAINT MONO (1689 2500);
FORCEPROP 2 LAST $XR1 44 
J 0
(1779 2500);
DISPLAY 0.638298 (1779 2500);
PAINT MONO (1779 2500);
FORCEPROP 2 LAST $XR2 45 
J 0
(1869 2500);
DISPLAY 0.638298 (1869 2500);
PAINT MONO (1869 2500);
FORCEPROP 2 LAST $XR3 46 
J 0
(1959 2500);
DISPLAY 0.638298 (1959 2500);
PAINT MONO (1959 2500);
FORCEPROP 2 LAST $XR4 47 
J 0
(2049 2500);
DISPLAY 0.638298 (2049 2500);
PAINT MONO (2049 2500);
FORCEPROP 2 LAST $XR5 48 
J 0
(2139 2500);
DISPLAY 0.638298 (2139 2500);
PAINT MONO (2139 2500);
FORCEPROP 2 LASTPIN (1450 2500) SIG_NAME FM_ADR_COMPLETE_ABC_N
J 2
(1440 2510);
DISPLAY 0.617021 (1440 2510);
PAINT ORANGE (1440 2510);
FORCEPROP 1 LAST COMMENT_BODY TRUE
J 0
(1455 2405);
DISPLAY 0.872340 (1455 2405);
PAINT GREEN (1455 2405);
DISPLAY INVISIBLE (1455 2405);
FORCEPROP 2 LAST CDS_LIB mstr_standard
J 0
(1500 2500);
PAINT ORANGE (1500 2500);
DISPLAY INVISIBLE (1500 2500);
FORCEPROP 1 LAST OFFPAGE TRUE
J 0
(1825 2375);
DISPLAY 0.872340 (1825 2375);
PAINT GREEN (1825 2375);
DISPLAY INVISIBLE (1825 2375);
FORCEPROP 2 LAST PATH I11
J 0
(1675 2575);
DISPLAY 1.021277 (1675 2575);
PAINT ORANGE (1675 2575);
DISPLAY INVISIBLE (1675 2575);
FORCEADD OFFPAGE..2
(1500 2200);
FORCEPROP 2 LAST $XR0 49 
J 0
(1689 2200);
DISPLAY 0.638298 (1689 2200);
PAINT MONO (1689 2200);
FORCEPROP 2 LAST $XR1 50 
J 0
(1779 2200);
DISPLAY 0.638298 (1779 2200);
PAINT MONO (1779 2200);
FORCEPROP 2 LAST $XR2 51 
J 0
(1869 2200);
DISPLAY 0.638298 (1869 2200);
PAINT MONO (1869 2200);
FORCEPROP 2 LAST $XR3 52 
J 0
(1959 2200);
DISPLAY 0.638298 (1959 2200);
PAINT MONO (1959 2200);
FORCEPROP 2 LAST $XR4 53 
J 0
(2049 2200);
DISPLAY 0.638298 (2049 2200);
PAINT MONO (2049 2200);
FORCEPROP 2 LAST $XR5 54 
J 0
(2139 2200);
DISPLAY 0.638298 (2139 2200);
PAINT MONO (2139 2200);
FORCEPROP 2 LASTPIN (1450 2200) SIG_NAME FM_ADR_COMPLETE_DEF_N
J 2
(1425 2210);
DISPLAY 0.617021 (1425 2210);
PAINT ORANGE (1425 2210);
FORCEPROP 2 LAST CDS_LIB mstr_standard
J 0
(1500 2200);
PAINT ORANGE (1500 2200);
DISPLAY INVISIBLE (1500 2200);
FORCEPROP 1 LAST COMMENT_BODY TRUE
J 0
(1455 2105);
DISPLAY 0.872340 (1455 2105);
PAINT GREEN (1455 2105);
DISPLAY INVISIBLE (1455 2105);
FORCEPROP 2 LAST PATH I12
J 0
(1675 2275);
DISPLAY 1.021277 (1675 2275);
PAINT ORANGE (1675 2275);
DISPLAY INVISIBLE (1675 2275);
FORCEPROP 1 LAST OFFPAGE TRUE
J 0
(1825 2075);
DISPLAY 0.872340 (1825 2075);
PAINT GREEN (1825 2075);
DISPLAY INVISIBLE (1825 2075);
FORCEADD OFFPAGE..2
(1500 1900);
FORCEPROP 2 LAST $XR0 77 
J 0
(1689 1900);
DISPLAY 0.638298 (1689 1900);
PAINT MONO (1689 1900);
FORCEPROP 2 LAST $XR1 78 
J 0
(1779 1900);
DISPLAY 0.638298 (1779 1900);
PAINT MONO (1779 1900);
FORCEPROP 2 LAST $XR2 79 
J 0
(1869 1900);
DISPLAY 0.638298 (1869 1900);
PAINT MONO (1869 1900);
FORCEPROP 2 LAST $XR3 80 
J 0
(1959 1900);
DISPLAY 0.638298 (1959 1900);
PAINT MONO (1959 1900);
FORCEPROP 2 LAST $XR4 81 
J 0
(2049 1900);
DISPLAY 0.638298 (2049 1900);
PAINT MONO (2049 1900);
FORCEPROP 2 LAST $XR5 82 
J 0
(2139 1900);
DISPLAY 0.638298 (2139 1900);
PAINT MONO (2139 1900);
FORCEPROP 2 LASTPIN (1450 1900) SIG_NAME FM_ADR_COMPLETE_GHJ_N
J 2
(1425 1910);
DISPLAY 0.617021 (1425 1910);
PAINT ORANGE (1425 1910);
FORCEPROP 1 LAST COMMENT_BODY TRUE
J 0
(1455 1805);
DISPLAY 0.872340 (1455 1805);
PAINT GREEN (1455 1805);
DISPLAY INVISIBLE (1455 1805);
FORCEPROP 2 LAST CDS_LIB mstr_standard
J 0
(1500 1900);
PAINT ORANGE (1500 1900);
DISPLAY INVISIBLE (1500 1900);
FORCEPROP 2 LAST PATH I13
J 0
(1675 1975);
DISPLAY 1.021277 (1675 1975);
PAINT ORANGE (1675 1975);
DISPLAY INVISIBLE (1675 1975);
FORCEPROP 1 LAST OFFPAGE TRUE
J 0
(1825 1775);
DISPLAY 0.872340 (1825 1775);
PAINT GREEN (1825 1775);
DISPLAY INVISIBLE (1825 1775);
FORCEADD OFFPAGE..2
(1500 1600);
FORCEPROP 2 LAST $XR0 83 
J 0
(1689 1600);
DISPLAY 0.638298 (1689 1600);
PAINT MONO (1689 1600);
FORCEPROP 2 LAST $XR1 84 
J 0
(1779 1600);
DISPLAY 0.638298 (1779 1600);
PAINT MONO (1779 1600);
FORCEPROP 2 LAST $XR2 85 
J 0
(1869 1600);
DISPLAY 0.638298 (1869 1600);
PAINT MONO (1869 1600);
FORCEPROP 2 LAST $XR3 86 
J 0
(1959 1600);
DISPLAY 0.638298 (1959 1600);
PAINT MONO (1959 1600);
FORCEPROP 2 LAST $XR4 87 
J 0
(2049 1600);
DISPLAY 0.638298 (2049 1600);
PAINT MONO (2049 1600);
FORCEPROP 2 LAST $XR5 88 
J 0
(2139 1600);
DISPLAY 0.638298 (2139 1600);
PAINT MONO (2139 1600);
FORCEPROP 2 LASTPIN (1450 1600) SIG_NAME FM_ADR_COMPLETE_KLM_N
J 2
(1425 1610);
DISPLAY 0.617021 (1425 1610);
PAINT ORANGE (1425 1610);
FORCEPROP 1 LAST COMMENT_BODY TRUE
J 0
(1455 1505);
DISPLAY 0.872340 (1455 1505);
PAINT GREEN (1455 1505);
DISPLAY INVISIBLE (1455 1505);
FORCEPROP 2 LAST CDS_LIB mstr_standard
J 0
(1500 1600);
PAINT ORANGE (1500 1600);
DISPLAY INVISIBLE (1500 1600);
FORCEPROP 1 LAST OFFPAGE TRUE
J 0
(1825 1475);
DISPLAY 0.872340 (1825 1475);
PAINT GREEN (1825 1475);
DISPLAY INVISIBLE (1825 1475);
FORCEPROP 2 LAST PATH I14
J 0
(1675 1675);
DISPLAY 1.021277 (1675 1675);
PAINT ORANGE (1675 1675);
DISPLAY INVISIBLE (1675 1675);
FORCEADD GND..1
(-550 1900);
FORCEPROP 3 LASTPIN (-550 1950) SIG_NAME GND\g
J 0
(-540 1960);
DISPLAY 0.659574 (-540 1960);
PAINT MONO (-540 1960);
DISPLAY INVISIBLE (-540 1960);
FORCEPROP 1 LAST VOLTAGE 0.0V
J 0
(-595 1857);
DISPLAY 0.340426 (-595 1857);
PAINT SKYBLUE (-595 1857);
DISPLAY INVISIBLE (-595 1857);
FORCEPROP 1 LAST BODY_TYPE PLUMBING
J 0
(-595 1857);
DISPLAY 0.340426 (-595 1857);
PAINT GREEN (-595 1857);
DISPLAY INVISIBLE (-595 1857);
FORCEPROP 2 LAST CDS_LIB mstr_symbols
J 0
(-550 1900);
PAINT ORANGE (-550 1900);
DISPLAY INVISIBLE (-550 1900);
FORCEPROP 1 LAST PATH I16
J 0
(-475 1900);
DISPLAY 0.872340 (-475 1900);
PAINT AQUA (-475 1900);
DISPLAY INVISIBLE (-475 1900);
FORCEPROP 1 LAST SIZE 1B
J 0
(-475 1850);
DISPLAY 0.872340 (-475 1850);
PAINT AQUA (-475 1850);
DISPLAY INVISIBLE (-475 1850);
FORCEPROP 1 LAST HDL_POWER GND
J 0
(-550 2050);
DISPLAY 0.872340 (-550 2050);
PAINT GREEN (-550 2050);
DISPLAY INVISIBLE (-550 2050);
FORCEADD PVPP_ABC..1
(-550 2950);
FORCEPROP 3 LASTPIN (-550 2900) SIG_NAME PVPP_ABC\g
J 0
(-540 2910);
DISPLAY 0.659574 (-540 2910);
PAINT MONO (-540 2910);
DISPLAY INVISIBLE (-540 2910);
FORCEPROP 1 LAST HDL_POWER PVPP_ABC
J 1
(-550 3000);
DISPLAY 0.872340 (-550 3000);
PAINT GREEN (-550 3000);
DISPLAY INVISIBLE (-550 3000);
FORCEPROP 1 LAST BODY_TYPE PLUMBING
J 0
(-595 2907);
DISPLAY 0.340426 (-595 2907);
PAINT GREEN (-595 2907);
DISPLAY INVISIBLE (-595 2907);
FORCEPROP 2 LAST CDS_LIB mstr_symbols
J 0
(-550 2950);
PAINT ORANGE (-550 2950);
DISPLAY INVISIBLE (-550 2950);
FORCEPROP 1 LAST VOLTAGE 2.5V
J 0
(-595 2907);
DISPLAY 0.340426 (-595 2907);
PAINT SKYBLUE (-595 2907);
DISPLAY INVISIBLE (-595 2907);
FORCEPROP 1 LAST PATH I17
J 0
(-500 2975);
DISPLAY 0.872340 (-500 2975);
PAINT AQUA (-500 2975);
DISPLAY INVISIBLE (-500 2975);
FORCEADD FET_N..8
(-550 2200);
FORCEPROP 1 LASTPIN (-550 2000) $PN 2
J 2
(-492 2000);
DISPLAY 0.617021 (-492 2000);
PAINT WHITE (-492 2000);
FORCEPROP 1 LAST PART_NUMBER C79254-001
J 0
(-350 2000);
DISPLAY 0.617021 (-350 2000);
PAINT BLUE (-350 2000);
FORCEPROP 1 LASTPIN (-750 2100) $PN 1
J 2
(-747 2115);
DISPLAY 0.617021 (-747 2115);
PAINT WHITE (-747 2115);
FORCEPROP 1 LASTPIN (-550 2400) $PN 3
J 2
(-497 2365);
DISPLAY 0.617021 (-497 2365);
PAINT WHITE (-497 2365);
FORCEPROP 1 LAST MATERIAL FET
J 0
(-350 2100);
DISPLAY 0.617021 (-350 2100);
PAINT SKYBLUE (-350 2100);
FORCEPROP 1 LAST VALUE 2N7002
J 0
(-350 2150);
DISPLAY 0.617021 (-350 2150);
PAINT SKYBLUE (-350 2150);
FORCEPROP 1 LAST LOCATION Q6F1
J 0
(-350 2200);
DISPLAY 0.617021 (-350 2200);
PAINT AQUA (-350 2200);
FORCEPROP 2 LAST CDS_LIB mstr_discrete
J 0
(-550 2200);
PAINT ORANGE (-550 2200);
DISPLAY INVISIBLE (-550 2200);
FORCEPROP 1 LAST PACK_TYPE SOT23
J 0
(-350 2050);
DISPLAY 0.978723 (-350 2050);
PAINT SKYBLUE (-350 2050);
DISPLAY INVISIBLE (-350 2050);
FORCEPROP 2 LAST CDS_LOCATION Q6F1
J 0
(-350 2200);
DISPLAY 0.617021 (-350 2200);
PAINT AQUA (-350 2200);
DISPLAY INVISIBLE (-350 2200);
FORCEPROP 1 LAST PATH I18
J 0
(-350 2250);
DISPLAY 0.978723 (-350 2250);
PAINT BLUE (-350 2250);
DISPLAY INVISIBLE (-350 2250);
FORCEPROP 0 LAST ROOM NVDIMM
J 0
(-350 2300);
DISPLAY 1.021277 (-350 2300);
PAINT ORANGE (-350 2300);
DISPLAY INVISIBLE (-350 2300);
FORCEPROP 2 LAST SEC 1
J 0
(-350 2300);
DISPLAY 0.680851 (-350 2300);
PAINT MONO (-350 2300);
DISPLAY INVISIBLE (-350 2300);
FORCEPROP 0 LAST BOM_COST MEM_NV
J 0
(-350 2300);
DISPLAY 1.021277 (-350 2300);
PAINT ORANGE (-350 2300);
DISPLAY INVISIBLE (-350 2300);
FORCEPROP 2 LAST SEC_TYPE SOT23
J 0
(-350 2300);
DISPLAY 1.021277 (-350 2300);
PAINT ORANGE (-350 2300);
DISPLAY INVISIBLE (-350 2300);
FORCEADD RES..1
(-1650 2100);
FORCEPROP 1 LAST VALUE 0.0
J 2
(-1675 2000);
DISPLAY 0.617021 (-1675 2000);
PAINT SKYBLUE (-1675 2000);
FORCEPROP 1 LAST TOLERANCE 5%
J 0
(-1650 2000);
DISPLAY 0.617021 (-1650 2000);
PAINT SKYBLUE (-1650 2000);
FORCEPROP 1 LAST PACK_TYPE 0402
J 0
(-1400 1950);
DISPLAY 0.617021 (-1400 1950);
PAINT SKYBLUE (-1400 1950);
FORCEPROP 1 LAST MATERIAL CHIP
J 0
(-1650 1950);
DISPLAY 0.617021 (-1650 1950);
PAINT SKYBLUE (-1650 1950);
FORCEPROP 1 LAST WATTAGE 1/16W
J 2
(-1675 1950);
DISPLAY 0.617021 (-1675 1950);
PAINT SKYBLUE (-1675 1950);
FORCEPROP 1 LASTPIN (-1750 2100) $PN 1
J 0
(-1738 2112);
DISPLAY 0.617021 (-1738 2112);
PAINT ORANGE (-1738 2112);
FORCEPROP 1 LAST LOCATION R4T1
J 0
(-1700 2150);
DISPLAY 0.617021 (-1700 2150);
PAINT AQUA (-1700 2150);
FORCEPROP 1 LASTPIN (-1550 2100) $PN 2
J 0
(-1588 2112);
DISPLAY 0.617021 (-1588 2112);
PAINT ORANGE (-1588 2112);
FORCEPROP 1 LAST PART_NUMBER G21497-005
J 0
(-1700 2200);
DISPLAY 0.617021 (-1700 2200);
PAINT BLUE (-1700 2200);
FORCEPROP 0 LAST ROOM NV_DIMM
J 0
(-1700 2250);
DISPLAY 1.021277 (-1700 2250);
PAINT ORANGE (-1700 2250);
DISPLAY INVISIBLE (-1700 2250);
FORCEPROP 1 LAST PATH I2
J 0
(-1700 2250);
DISPLAY 0.978723 (-1700 2250);
PAINT WHITE (-1700 2250);
DISPLAY INVISIBLE (-1700 2250);
FORCEPROP 2 LAST CDS_LOCATION R4T1
J 0
(-1700 2150);
DISPLAY 0.617021 (-1700 2150);
PAINT AQUA (-1700 2150);
DISPLAY INVISIBLE (-1700 2150);
FORCEPROP 0 LAST SEC 1
J 0
(-1700 2250);
DISPLAY 0.680851 (-1700 2250);
PAINT MONO (-1700 2250);
DISPLAY INVISIBLE (-1700 2250);
FORCEPROP 2 LAST CDS_LIB mstr_discrete
J 0
(-1650 2100);
PAINT ORANGE (-1650 2100);
DISPLAY INVISIBLE (-1650 2100);
FORCEPROP 0 LAST BOM_COST MEM_NV
J 0
(-1700 2300);
DISPLAY 1.021277 (-1700 2300);
PAINT ORANGE (-1700 2300);
DISPLAY INVISIBLE (-1700 2300);
FORCEPROP 2 LAST SEC_TYPE 0402
J 0
(-1700 2300);
DISPLAY 1.021277 (-1700 2300);
PAINT ORANGE (-1700 2300);
DISPLAY INVISIBLE (-1700 2300);
FORCEADD OFFPAGE..2
(4000 2900);
FORCEPROP 2 LAST $XR0 156 
J 0
(4189 2900);
DISPLAY 0.638298 (4189 2900);
PAINT MONO (4189 2900);
FORCEPROP 2 LAST $XR1 157 
J 0
(4309 2900);
DISPLAY 0.638298 (4309 2900);
PAINT MONO (4309 2900);
FORCEPROP 2 LAST $XR2 191 
J 0
(4429 2900);
DISPLAY 0.638298 (4429 2900);
PAINT MONO (4429 2900);
FORCEPROP 2 LAST $XR3 120 
J 0
(4549 2900);
DISPLAY 0.638298 (4549 2900);
PAINT MONO (4549 2900);
FORCEPROP 1 LAST COMMENT_BODY TRUE
J 0
(3955 2805);
DISPLAY 0.872340 (3955 2805);
PAINT GREEN (3955 2805);
DISPLAY INVISIBLE (3955 2805);
FORCEPROP 2 LAST CDS_LIB mstr_standard
J 0
(4000 2900);
PAINT MONO (4000 2900);
DISPLAY INVISIBLE (4000 2900);
FORCEPROP 2 LAST PATH I22
J 0
(4175 2975);
DISPLAY 1.021277 (4175 2975);
PAINT ORANGE (4175 2975);
DISPLAY INVISIBLE (4175 2975);
FORCEPROP 1 LAST OFFPAGE TRUE
J 0
(4325 2775);
DISPLAY 0.872340 (4325 2775);
PAINT GREEN (4325 2775);
DISPLAY INVISIBLE (4325 2775);
FORCEADD RES..1
(3325 2900);
FORCEPROP 1 LAST WATTAGE 1/16W
J 2
(3300 2750);
DISPLAY 0.617021 (3300 2750);
PAINT SKYBLUE (3300 2750);
FORCEPROP 1 LAST VALUE 0.0
J 2
(3300 2800);
DISPLAY 0.617021 (3300 2800);
PAINT SKYBLUE (3300 2800);
FORCEPROP 1 LAST TOLERANCE 5%
J 0
(3325 2800);
DISPLAY 0.617021 (3325 2800);
PAINT SKYBLUE (3325 2800);
FORCEPROP 1 LAST PART_NUMBER G21497-005
J 0
(3275 3000);
DISPLAY 0.617021 (3275 3000);
PAINT BLUE (3275 3000);
FORCEPROP 1 LAST LOCATION R2P12
J 0
(3275 2950);
DISPLAY 0.617021 (3275 2950);
PAINT AQUA (3275 2950);
FORCEPROP 1 LAST MATERIAL EMPTY
J 0
(3325 2750);
DISPLAY 0.617021 (3325 2750);
PAINT RED (3325 2750);
FORCEPROP 1 LAST PACK_TYPE 0402
J 0
(3575 2750);
DISPLAY 0.617021 (3575 2750);
PAINT SKYBLUE (3575 2750);
FORCEPROP 2 LAST CDS_LIB mstr_discrete
J 0
(3325 2900);
PAINT MONO (3325 2900);
DISPLAY INVISIBLE (3325 2900);
FORCEPROP 1 LASTPIN (3225 2900) $PN 1
J 0
(3237 2912);
DISPLAY 0.787234 (3237 2912);
PAINT ORANGE (3237 2912);
DISPLAY INVISIBLE (3237 2912);
FORCEPROP 2 LAST CDS_LOCATION R2P12
J 0
(3275 2950);
DISPLAY 0.617021 (3275 2950);
PAINT AQUA (3275 2950);
DISPLAY INVISIBLE (3275 2950);
FORCEPROP 1 LASTPIN (3425 2900) $PN 2
J 0
(3387 2912);
DISPLAY 0.787234 (3387 2912);
PAINT ORANGE (3387 2912);
DISPLAY INVISIBLE (3387 2912);
FORCEPROP 1 LAST PATH I23
J 0
(3275 3050);
DISPLAY 0.978723 (3275 3050);
PAINT WHITE (3275 3050);
DISPLAY INVISIBLE (3275 3050);
FORCEPROP 0 LAST ROOM NV_DIMM
J 0
(3275 3100);
DISPLAY 1.021277 (3275 3100);
PAINT ORANGE (3275 3100);
DISPLAY INVISIBLE (3275 3100);
FORCEPROP 2 LAST $SEC 1
J 0
(3275 3100);
PAINT MONO (3275 3100);
DISPLAY INVISIBLE (3275 3100);
FORCEPROP 2 LAST CDS_SEC 1
J 0
(3275 3100);
PAINT MONO (3275 3100);
DISPLAY INVISIBLE (3275 3100);
FORCEPROP 0 LAST BOM_COST MEM_NV
J 0
(3275 3200);
DISPLAY 1.021277 (3275 3200);
PAINT ORANGE (3275 3200);
DISPLAY INVISIBLE (3275 3200);
FORCEADD RES..2
(1850 3875);
FORCEPROP 1 LAST MATERIAL CHIP
J 0
(1890 3800);
DISPLAY 0.617021 (1890 3800);
PAINT SKYBLUE (1890 3800);
FORCEPROP 1 LAST PACK_TYPE 0402
J 0
(1890 3700);
DISPLAY 0.617021 (1890 3700);
PAINT SKYBLUE (1890 3700);
FORCEPROP 1 LAST WATTAGE 1/16W
J 0
(1890 3850);
DISPLAY 0.617021 (1890 3850);
PAINT SKYBLUE (1890 3850);
FORCEPROP 1 LAST TOLERANCE 1%
J 0
(1895 3900);
DISPLAY 0.617021 (1895 3900);
PAINT SKYBLUE (1895 3900);
FORCEPROP 1 LAST VALUE 4.75K
J 0
(1895 3950);
DISPLAY 0.617021 (1895 3950);
PAINT SKYBLUE (1895 3950);
FORCEPROP 1 LAST LOCATION R8D29
J 0
(1895 4000);
DISPLAY 0.617021 (1895 4000);
PAINT AQUA (1895 4000);
FORCEPROP 1 LAST PART_NUMBER G21796-072
J 0
(1890 3750);
DISPLAY 0.617021 (1890 3750);
PAINT BLUE (1890 3750);
FORCEPROP 1 LASTPIN (1850 3775) $PN 2
J 0
(1855 3785);
DISPLAY 0.787234 (1855 3785);
PAINT ORANGE (1855 3785);
DISPLAY INVISIBLE (1855 3785);
FORCEPROP 2 LAST CDS_LIB mstr_discrete
J 0
(1850 3875);
PAINT MONO (1850 3875);
DISPLAY INVISIBLE (1850 3875);
FORCEPROP 1 LASTPIN (1850 3975) $PN 1
J 0
(1855 3937);
DISPLAY 0.787234 (1855 3937);
PAINT ORANGE (1855 3937);
DISPLAY INVISIBLE (1855 3937);
FORCEPROP 1 LAST PATH I26
J 0
(1900 4050);
DISPLAY 0.978723 (1900 4050);
PAINT WHITE (1900 4050);
DISPLAY INVISIBLE (1900 4050);
FORCEPROP 2 LAST CDS_LOCATION R8D29
J 0
(1895 4000);
DISPLAY 0.617021 (1895 4000);
PAINT AQUA (1895 4000);
DISPLAY INVISIBLE (1895 4000);
FORCEPROP 0 LAST ROOM NVDIMM
J 0
(1900 4100);
DISPLAY 1.021277 (1900 4100);
PAINT ORANGE (1900 4100);
DISPLAY INVISIBLE (1900 4100);
FORCEPROP 2 LAST $SEC 1
J 0
(1900 4100);
PAINT MONO (1900 4100);
DISPLAY INVISIBLE (1900 4100);
FORCEPROP 2 LAST CDS_SEC 1
J 0
(1900 4100);
PAINT MONO (1900 4100);
DISPLAY INVISIBLE (1900 4100);
FORCEADD RES..2
(2550 4100);
FORCEPROP 1 LAST MATERIAL CHIP
J 0
(2590 4025);
DISPLAY 0.617021 (2590 4025);
PAINT SKYBLUE (2590 4025);
FORCEPROP 1 LAST PACK_TYPE 0402
J 0
(2590 3925);
DISPLAY 0.617021 (2590 3925);
PAINT SKYBLUE (2590 3925);
FORCEPROP 1 LAST PART_NUMBER G21796-072
J 0
(2590 3975);
DISPLAY 0.617021 (2590 3975);
PAINT BLUE (2590 3975);
FORCEPROP 1 LAST WATTAGE 1/16W
J 0
(2590 4075);
DISPLAY 0.617021 (2590 4075);
PAINT SKYBLUE (2590 4075);
FORCEPROP 1 LAST TOLERANCE 1%
J 0
(2595 4125);
DISPLAY 0.617021 (2595 4125);
PAINT SKYBLUE (2595 4125);
FORCEPROP 1 LAST VALUE 4.75K
J 0
(2595 4175);
DISPLAY 0.617021 (2595 4175);
PAINT SKYBLUE (2595 4175);
FORCEPROP 1 LAST LOCATION R8D31
J 0
(2595 4225);
DISPLAY 0.617021 (2595 4225);
PAINT AQUA (2595 4225);
FORCEPROP 1 LASTPIN (2550 4000) $PN 2
J 0
(2555 4010);
DISPLAY 0.787234 (2555 4010);
PAINT ORANGE (2555 4010);
DISPLAY INVISIBLE (2555 4010);
FORCEPROP 1 LASTPIN (2550 4200) $PN 1
J 0
(2555 4162);
DISPLAY 0.787234 (2555 4162);
PAINT ORANGE (2555 4162);
DISPLAY INVISIBLE (2555 4162);
FORCEPROP 2 LAST CDS_LIB mstr_discrete
J 0
(2550 4100);
PAINT MONO (2550 4100);
DISPLAY INVISIBLE (2550 4100);
FORCEPROP 0 LAST ROOM NVDIMM
J 0
(2600 4325);
DISPLAY 1.021277 (2600 4325);
PAINT ORANGE (2600 4325);
DISPLAY INVISIBLE (2600 4325);
FORCEPROP 1 LAST PATH I27
J 0
(2600 4275);
DISPLAY 0.978723 (2600 4275);
PAINT WHITE (2600 4275);
DISPLAY INVISIBLE (2600 4275);
FORCEPROP 2 LAST CDS_LOCATION R8D31
J 0
(2595 4225);
DISPLAY 0.617021 (2595 4225);
PAINT AQUA (2595 4225);
DISPLAY INVISIBLE (2595 4225);
FORCEPROP 2 LAST $SEC 1
J 0
(2600 4325);
PAINT MONO (2600 4325);
DISPLAY INVISIBLE (2600 4325);
FORCEPROP 2 LAST CDS_SEC 1
J 0
(2600 4325);
PAINT MONO (2600 4325);
DISPLAY INVISIBLE (2600 4325);
FORCEADD P3V3_STBY..1
(1850 4100);
FORCEPROP 3 LASTPIN (1850 4050) SIG_NAME P3V3_STBY\g
J 0
(1860 4060);
DISPLAY 0.659574 (1860 4060);
PAINT MONO (1860 4060);
DISPLAY INVISIBLE (1860 4060);
FORCEPROP 1 LAST HDL_POWER P3V3_STBY
J 0
(1550 3975);
DISPLAY 0.872340 (1550 3975);
PAINT ORANGE (1550 3975);
DISPLAY INVISIBLE (1550 3975);
FORCEPROP 1 LAST VOLTAGE 3.3V
J 0
(1805 4057);
DISPLAY 0.340426 (1805 4057);
PAINT SKYBLUE (1805 4057);
DISPLAY INVISIBLE (1805 4057);
FORCEPROP 1 LAST BODY_TYPE PLUMBING
J 0
(1805 4057);
DISPLAY 0.340426 (1805 4057);
PAINT GREEN (1805 4057);
DISPLAY INVISIBLE (1805 4057);
FORCEPROP 1 LAST PATH I28
J 0
(1895 4102);
DISPLAY 0.340426 (1895 4102);
PAINT GREEN (1895 4102);
DISPLAY INVISIBLE (1895 4102);
FORCEPROP 1 LAST SIZE 1B
J 0
(1895 4122);
DISPLAY 0.340426 (1895 4122);
PAINT GREEN (1895 4122);
DISPLAY INVISIBLE (1895 4122);
FORCEPROP 2 LAST CDS_LIB mstr_symbols
J 0
(1850 4100);
PAINT MONO (1850 4100);
DISPLAY INVISIBLE (1850 4100);
FORCEADD P3V3_STBY..1
(2550 4325);
FORCEPROP 3 LASTPIN (2550 4275) SIG_NAME P3V3_STBY\g
J 0
(2560 4285);
DISPLAY 0.659574 (2560 4285);
PAINT MONO (2560 4285);
DISPLAY INVISIBLE (2560 4285);
FORCEPROP 1 LAST BODY_TYPE PLUMBING
J 0
(2505 4282);
DISPLAY 0.340426 (2505 4282);
PAINT GREEN (2505 4282);
DISPLAY INVISIBLE (2505 4282);
FORCEPROP 1 LAST VOLTAGE 3.3V
J 0
(2505 4282);
DISPLAY 0.340426 (2505 4282);
PAINT SKYBLUE (2505 4282);
DISPLAY INVISIBLE (2505 4282);
FORCEPROP 2 LAST CDS_LIB mstr_symbols
J 0
(2550 4325);
PAINT MONO (2550 4325);
DISPLAY INVISIBLE (2550 4325);
FORCEPROP 1 LAST HDL_POWER P3V3_STBY
J 0
(2250 4200);
DISPLAY 0.872340 (2250 4200);
PAINT ORANGE (2250 4200);
DISPLAY INVISIBLE (2250 4200);
FORCEPROP 1 LAST PATH I29
J 0
(2595 4327);
DISPLAY 0.340426 (2595 4327);
PAINT GREEN (2595 4327);
DISPLAY INVISIBLE (2595 4327);
FORCEPROP 1 LAST SIZE 1B
J 0
(2595 4347);
DISPLAY 0.340426 (2595 4347);
PAINT GREEN (2595 4347);
DISPLAY INVISIBLE (2595 4347);
FORCEADD RES..1
(450 2500);
FORCEPROP 1 LAST VALUE 49.9
J 2
(425 2400);
DISPLAY 0.617021 (425 2400);
PAINT SKYBLUE (425 2400);
FORCEPROP 1 LAST WATTAGE 1/16W
J 2
(425 2350);
DISPLAY 0.617021 (425 2350);
PAINT SKYBLUE (425 2350);
FORCEPROP 1 LASTPIN (350 2500) $PN 1
J 0
(362 2512);
DISPLAY 0.617021 (362 2512);
PAINT ORANGE (362 2512);
FORCEPROP 1 LAST TOLERANCE 1%
J 0
(450 2400);
DISPLAY 0.617021 (450 2400);
PAINT SKYBLUE (450 2400);
FORCEPROP 1 LASTPIN (550 2500) $PN 2
J 0
(512 2512);
DISPLAY 0.617021 (512 2512);
PAINT ORANGE (512 2512);
FORCEPROP 1 LAST MATERIAL CHIP
J 0
(450 2350);
DISPLAY 0.617021 (450 2350);
PAINT SKYBLUE (450 2350);
FORCEPROP 1 LAST PART_NUMBER G21796-047
J 0
(400 2600);
DISPLAY 0.617021 (400 2600);
PAINT BLUE (400 2600);
FORCEPROP 1 LAST LOCATION R6F4
J 0
(400 2550);
DISPLAY 0.617021 (400 2550);
PAINT AQUA (400 2550);
FORCEPROP 1 LAST PACK_TYPE 0402
J 0
(700 2350);
DISPLAY 0.617021 (700 2350);
PAINT SKYBLUE (700 2350);
FORCEPROP 2 LAST CDS_LIB mstr_discrete
J 0
(450 2500);
PAINT ORANGE (450 2500);
DISPLAY INVISIBLE (450 2500);
FORCEPROP 2 LAST CDS_LOCATION R6F4
J 0
(400 2550);
DISPLAY 0.617021 (400 2550);
PAINT AQUA (400 2550);
DISPLAY INVISIBLE (400 2550);
FORCEPROP 0 LAST ROOM NV_DIMM
J 0
(400 2650);
DISPLAY 1.021277 (400 2650);
PAINT ORANGE (400 2650);
DISPLAY INVISIBLE (400 2650);
FORCEPROP 1 LAST PATH I3
J 0
(400 2650);
DISPLAY 0.978723 (400 2650);
PAINT WHITE (400 2650);
DISPLAY INVISIBLE (400 2650);
FORCEPROP 0 LAST SEC 1
J 0
(400 2650);
DISPLAY 0.680851 (400 2650);
PAINT MONO (400 2650);
DISPLAY INVISIBLE (400 2650);
FORCEPROP 2 LAST SEC_TYPE 0402
J 0
(400 2700);
DISPLAY 1.021277 (400 2700);
PAINT ORANGE (400 2700);
DISPLAY INVISIBLE (400 2700);
FORCEPROP 0 LAST BOM_COST MEM_NV
J 0
(400 2700);
DISPLAY 1.021277 (400 2700);
PAINT ORANGE (400 2700);
DISPLAY INVISIBLE (400 2700);
FORCEADD GND..1
(2550 3325);
FORCEPROP 3 LASTPIN (2550 3375) SIG_NAME GND\g
J 0
(2560 3385);
DISPLAY 0.659574 (2560 3385);
PAINT MONO (2560 3385);
DISPLAY INVISIBLE (2560 3385);
FORCEPROP 1 LAST BODY_TYPE PLUMBING
J 0
(2505 3282);
DISPLAY 0.340426 (2505 3282);
PAINT GREEN (2505 3282);
DISPLAY INVISIBLE (2505 3282);
FORCEPROP 1 LAST VOLTAGE 0.0V
J 0
(2505 3282);
DISPLAY 0.340426 (2505 3282);
PAINT SKYBLUE (2505 3282);
DISPLAY INVISIBLE (2505 3282);
FORCEPROP 2 LAST CDS_LIB mstr_symbols
J 0
(2550 3325);
PAINT MONO (2550 3325);
DISPLAY INVISIBLE (2550 3325);
FORCEPROP 1 LAST HDL_POWER GND
J 0
(2550 3475);
DISPLAY 0.872340 (2550 3475);
PAINT GREEN (2550 3475);
DISPLAY INVISIBLE (2550 3475);
FORCEPROP 1 LAST SIZE 1B
J 0
(2625 3275);
DISPLAY 0.872340 (2625 3275);
PAINT AQUA (2625 3275);
DISPLAY INVISIBLE (2625 3275);
FORCEPROP 1 LAST PATH I30
J 0
(2625 3325);
DISPLAY 0.872340 (2625 3325);
PAINT AQUA (2625 3325);
DISPLAY INVISIBLE (2625 3325);
FORCEADD GND..1
(1850 2850);
FORCEPROP 3 LASTPIN (1850 2900) SIG_NAME GND\g
J 0
(1860 2910);
DISPLAY 0.659574 (1860 2910);
PAINT MONO (1860 2910);
DISPLAY INVISIBLE (1860 2910);
FORCEPROP 1 LAST SIZE 1B
J 0
(1925 2800);
DISPLAY 0.872340 (1925 2800);
PAINT AQUA (1925 2800);
DISPLAY INVISIBLE (1925 2800);
FORCEPROP 1 LAST BODY_TYPE PLUMBING
J 0
(1805 2807);
DISPLAY 0.340426 (1805 2807);
PAINT GREEN (1805 2807);
DISPLAY INVISIBLE (1805 2807);
FORCEPROP 1 LAST VOLTAGE 0.0V
J 0
(1805 2807);
DISPLAY 0.340426 (1805 2807);
PAINT SKYBLUE (1805 2807);
DISPLAY INVISIBLE (1805 2807);
FORCEPROP 2 LAST CDS_LIB mstr_symbols
J 0
(1850 2850);
PAINT MONO (1850 2850);
DISPLAY INVISIBLE (1850 2850);
FORCEPROP 1 LAST HDL_POWER GND
J 0
(1850 3000);
DISPLAY 0.872340 (1850 3000);
PAINT GREEN (1850 3000);
DISPLAY INVISIBLE (1850 3000);
FORCEPROP 1 LAST PATH I31
J 0
(1925 2850);
DISPLAY 0.872340 (1925 2850);
PAINT AQUA (1925 2850);
DISPLAY INVISIBLE (1925 2850);
FORCEADD OFFPAGE..2
(3600 3925);
FORCEPROP 2 LAST $XR0 120 
J 0
(3789 3925);
DISPLAY 0.638298 (3789 3925);
PAINT MONO (3789 3925);
FORCEPROP 2 LAST $XR1 144 
J 0
(3909 3925);
DISPLAY 0.638298 (3909 3925);
PAINT MONO (3909 3925);
FORCEPROP 1 LAST COMMENT_BODY TRUE
J 0
(3555 3830);
DISPLAY 0.872340 (3555 3830);
PAINT GREEN (3555 3830);
DISPLAY INVISIBLE (3555 3830);
FORCEPROP 2 LAST PATH I33
J 0
(3650 4000);
DISPLAY 1.021277 (3650 4000);
PAINT ORANGE (3650 4000);
DISPLAY INVISIBLE (3650 4000);
FORCEPROP 2 LAST CDS_LIB mstr_standard
J 0
(3600 3925);
PAINT MONO (3600 3925);
DISPLAY INVISIBLE (3600 3925);
FORCEPROP 1 LAST OFFPAGE TRUE
J 0
(3925 3800);
DISPLAY 0.872340 (3925 3800);
PAINT GREEN (3925 3800);
DISPLAY INVISIBLE (3925 3800);
FORCEADD RES..1
(875 3075);
FORCEPROP 1 LAST WATTAGE 1/16W
J 2
(850 2925);
DISPLAY 0.617021 (850 2925);
PAINT SKYBLUE (850 2925);
FORCEPROP 1 LAST MATERIAL CHIP
J 0
(875 2925);
DISPLAY 0.617021 (875 2925);
PAINT SKYBLUE (875 2925);
FORCEPROP 1 LAST TOLERANCE 1%
J 0
(875 2975);
DISPLAY 0.617021 (875 2975);
PAINT SKYBLUE (875 2975);
FORCEPROP 1 LAST VALUE 10.0K
J 2
(850 2975);
DISPLAY 0.617021 (850 2975);
PAINT SKYBLUE (850 2975);
FORCEPROP 1 LASTPIN (775 3075) $PN 1
J 0
(787 3087);
DISPLAY 0.617021 (787 3087);
PAINT ORANGE (787 3087);
FORCEPROP 1 LAST LOCATION R8D30
J 0
(825 3125);
DISPLAY 0.617021 (825 3125);
PAINT AQUA (825 3125);
FORCEPROP 1 LASTPIN (975 3075) $PN 2
J 0
(937 3087);
DISPLAY 0.617021 (937 3087);
PAINT ORANGE (937 3087);
FORCEPROP 1 LAST PART_NUMBER G21796-016
J 0
(825 3175);
DISPLAY 0.617021 (825 3175);
PAINT BLUE (825 3175);
FORCEPROP 1 LAST PACK_TYPE 0402
J 0
(1125 2925);
DISPLAY 0.617021 (1125 2925);
PAINT SKYBLUE (1125 2925);
FORCEPROP 2 LAST SEC_TYPE 0402
J 0
(825 3275);
DISPLAY 1.021277 (825 3275);
PAINT ORANGE (825 3275);
DISPLAY INVISIBLE (825 3275);
FORCEPROP 2 LAST CDS_LIB mstr_discrete
J 0
(875 3075);
PAINT ORANGE (875 3075);
DISPLAY INVISIBLE (875 3075);
FORCEPROP 0 LAST BOM_COST MEM_NV
J 0
(825 3275);
DISPLAY 1.021277 (825 3275);
PAINT ORANGE (825 3275);
DISPLAY INVISIBLE (825 3275);
FORCEPROP 2 LAST SEC 1
J 0
(825 3275);
DISPLAY 0.680851 (825 3275);
PAINT MONO (825 3275);
DISPLAY INVISIBLE (825 3275);
FORCEPROP 2 LAST CDS_LOCATION R8D30
J 0
(825 3125);
DISPLAY 0.617021 (825 3125);
PAINT AQUA (825 3125);
DISPLAY INVISIBLE (825 3125);
FORCEPROP 1 LAST PATH I34
J 0
(825 3225);
DISPLAY 0.978723 (825 3225);
PAINT WHITE (825 3225);
DISPLAY INVISIBLE (825 3225);
FORCEPROP 0 LAST ROOM NV_DIMM
J 0
(825 3225);
DISPLAY 1.021277 (825 3225);
PAINT ORANGE (825 3225);
DISPLAY INVISIBLE (825 3225);
FORCEADD NPN_DUAL..1
(1800 3075);
FORCEPROP 1 LASTPIN (1850 2975) $PN 4
J 2
(1840 2975);
DISPLAY 0.617021 (1840 2975);
PAINT AQUA (1840 2975);
FORCEPROP 1 LASTPIN (1700 3075) $PN 5
J 0
(1715 3080);
DISPLAY 0.617021 (1715 3080);
PAINT AQUA (1715 3080);
FORCEPROP 1 LASTPIN (1850 3175) $PN 3
J 0
(1790 3135);
DISPLAY 0.617021 (1790 3135);
PAINT AQUA (1790 3135);
FORCEPROP 1 LAST MATERIAL XSTR
J 0
(1900 3075);
DISPLAY 0.617021 (1900 3075);
PAINT SKYBLUE (1900 3075);
FORCEPROP 1 LAST LOCATION Q8D1
J 0
(1900 3175);
DISPLAY 0.617021 (1900 3175);
PAINT AQUA (1900 3175);
FORCEPROP 1 LAST VALUE MBT3904
J 0
(1900 3125);
DISPLAY 0.617021 (1900 3125);
PAINT SKYBLUE (1900 3125);
FORCEPROP 1 LAST PART_NUMBER C52264-001
J 0
(1900 3025);
DISPLAY 0.617021 (1900 3025);
PAINT BLUE (1900 3025);
FORCEPROP 0 LAST ROOM NV_DIMM
J 0
(1900 3275);
DISPLAY 1.021277 (1900 3275);
PAINT ORANGE (1900 3275);
DISPLAY INVISIBLE (1900 3275);
FORCEPROP 2 LAST CDS_LOCATION Q8D1
J 0
(1900 3175);
DISPLAY 0.617021 (1900 3175);
PAINT AQUA (1900 3175);
DISPLAY INVISIBLE (1900 3175);
FORCEPROP 2 LAST SEC 1
J 0
(1900 3225);
DISPLAY 0.680851 (1900 3225);
PAINT MONO (1900 3225);
DISPLAY INVISIBLE (1900 3225);
FORCEPROP 2 LAST CDS_LIB mstr_discrete
J 0
(1800 3075);
PAINT ORANGE (1800 3075);
DISPLAY INVISIBLE (1800 3075);
FORCEPROP 2 LAST SEC_TYPE SSOPLF
J 0
(1900 3225);
DISPLAY 1.021277 (1900 3225);
PAINT ORANGE (1900 3225);
DISPLAY INVISIBLE (1900 3225);
FORCEPROP 0 LAST BOM_COST MEM_NV
J 0
(1900 3275);
DISPLAY 1.021277 (1900 3275);
PAINT ORANGE (1900 3275);
DISPLAY INVISIBLE (1900 3275);
FORCEPROP 1 LAST PACK_TYPE SSOPLF
J 0
(1900 3225);
DISPLAY 0.978723 (1900 3225);
PAINT SKYBLUE (1900 3225);
DISPLAY INVISIBLE (1900 3225);
FORCEPROP 1 LAST PATH I35
J 0
(2300 3075);
DISPLAY 0.978723 (2300 3075);
PAINT BLUE (2300 3075);
DISPLAY INVISIBLE (2300 3075);
FORCEADD NPN_DUAL..1
(2500 3550);
FORCEPROP 1 LASTPIN (2400 3550) $PN 2
J 0
(2415 3555);
DISPLAY 0.617021 (2415 3555);
PAINT AQUA (2415 3555);
FORCEPROP 1 LASTPIN (2550 3450) $PN 1
J 2
(2540 3450);
DISPLAY 0.617021 (2540 3450);
PAINT AQUA (2540 3450);
FORCEPROP 1 LASTPIN (2550 3650) $PN 6
J 0
(2490 3610);
DISPLAY 0.617021 (2490 3610);
PAINT AQUA (2490 3610);
FORCEPROP 1 LAST PART_NUMBER C52264-001
J 0
(2600 3500);
DISPLAY 0.617021 (2600 3500);
PAINT BLUE (2600 3500);
FORCEPROP 1 LAST MATERIAL XSTR
J 0
(2600 3550);
DISPLAY 0.617021 (2600 3550);
PAINT SKYBLUE (2600 3550);
FORCEPROP 1 LAST VALUE MBT3904
J 0
(2600 3600);
DISPLAY 0.617021 (2600 3600);
PAINT SKYBLUE (2600 3600);
FORCEPROP 1 LAST LOCATION Q8D1
J 0
(2600 3650);
DISPLAY 0.617021 (2600 3650);
PAINT AQUA (2600 3650);
FORCEPROP 2 LAST CDS_LIB mstr_discrete
J 0
(2500 3550);
PAINT ORANGE (2500 3550);
DISPLAY INVISIBLE (2500 3550);
FORCEPROP 1 LAST PATH I36
J 0
(3000 3550);
DISPLAY 0.978723 (3000 3550);
PAINT BLUE (3000 3550);
DISPLAY INVISIBLE (3000 3550);
FORCEPROP 0 LAST ROOM NV_DIMM
J 0
(2600 3750);
DISPLAY 1.021277 (2600 3750);
PAINT ORANGE (2600 3750);
DISPLAY INVISIBLE (2600 3750);
FORCEPROP 2 LAST CDS_LOCATION Q8D1
J 0
(2600 3650);
DISPLAY 0.617021 (2600 3650);
PAINT AQUA (2600 3650);
DISPLAY INVISIBLE (2600 3650);
FORCEPROP 2 LAST SEC 2
J 0
(2600 3700);
DISPLAY 0.680851 (2600 3700);
PAINT MONO (2600 3700);
DISPLAY INVISIBLE (2600 3700);
FORCEPROP 2 LAST SEC_TYPE SSOPLF
J 0
(2600 3700);
DISPLAY 1.021277 (2600 3700);
PAINT ORANGE (2600 3700);
DISPLAY INVISIBLE (2600 3700);
FORCEPROP 0 LAST BOM_COST MEM_NV
J 0
(2600 3850);
DISPLAY 1.021277 (2600 3850);
PAINT ORANGE (2600 3850);
DISPLAY INVISIBLE (2600 3850);
FORCEPROP 1 LAST PACK_TYPE SSOPLF
J 0
(2600 3700);
DISPLAY 0.978723 (2600 3700);
PAINT SKYBLUE (2600 3700);
DISPLAY INVISIBLE (2600 3700);
FORCEADD RES..1
(450 2200);
FORCEPROP 1 LAST VALUE 49.9
J 2
(425 2100);
DISPLAY 0.617021 (425 2100);
PAINT SKYBLUE (425 2100);
FORCEPROP 1 LAST WATTAGE 1/16W
J 2
(425 2050);
DISPLAY 0.617021 (425 2050);
PAINT SKYBLUE (425 2050);
FORCEPROP 1 LASTPIN (350 2200) $PN 1
J 0
(362 2212);
DISPLAY 0.617021 (362 2212);
PAINT ORANGE (362 2212);
FORCEPROP 1 LAST TOLERANCE 1%
J 0
(450 2100);
DISPLAY 0.617021 (450 2100);
PAINT SKYBLUE (450 2100);
FORCEPROP 1 LASTPIN (550 2200) $PN 2
J 0
(512 2212);
DISPLAY 0.617021 (512 2212);
PAINT ORANGE (512 2212);
FORCEPROP 1 LAST MATERIAL CHIP
J 0
(450 2050);
DISPLAY 0.617021 (450 2050);
PAINT SKYBLUE (450 2050);
FORCEPROP 1 LAST PART_NUMBER G21796-047
J 0
(400 2300);
DISPLAY 0.617021 (400 2300);
PAINT BLUE (400 2300);
FORCEPROP 1 LAST LOCATION R6F1
J 0
(400 2250);
DISPLAY 0.617021 (400 2250);
PAINT AQUA (400 2250);
FORCEPROP 1 LAST PACK_TYPE 0402
J 0
(700 2050);
DISPLAY 0.617021 (700 2050);
PAINT SKYBLUE (700 2050);
FORCEPROP 2 LAST CDS_LOCATION R6F1
J 0
(400 2250);
DISPLAY 0.617021 (400 2250);
PAINT AQUA (400 2250);
DISPLAY INVISIBLE (400 2250);
FORCEPROP 2 LAST CDS_LIB mstr_discrete
J 0
(450 2200);
PAINT ORANGE (450 2200);
DISPLAY INVISIBLE (450 2200);
FORCEPROP 0 LAST BOM_COST MEM_NV
J 0
(400 2400);
DISPLAY 1.021277 (400 2400);
PAINT ORANGE (400 2400);
DISPLAY INVISIBLE (400 2400);
FORCEPROP 2 LAST SEC_TYPE 0402
J 0
(400 2400);
DISPLAY 1.021277 (400 2400);
PAINT ORANGE (400 2400);
DISPLAY INVISIBLE (400 2400);
FORCEPROP 0 LAST SEC 1
J 0
(400 2350);
DISPLAY 0.680851 (400 2350);
PAINT MONO (400 2350);
DISPLAY INVISIBLE (400 2350);
FORCEPROP 1 LAST PATH I4
J 0
(400 2350);
DISPLAY 0.978723 (400 2350);
PAINT WHITE (400 2350);
DISPLAY INVISIBLE (400 2350);
FORCEPROP 0 LAST ROOM NV_DIMM
J 0
(400 2350);
DISPLAY 1.021277 (400 2350);
PAINT ORANGE (400 2350);
DISPLAY INVISIBLE (400 2350);
FORCEADD RES..1
(450 1900);
FORCEPROP 1 LAST WATTAGE 1/16W
J 2
(425 1750);
DISPLAY 0.617021 (425 1750);
PAINT SKYBLUE (425 1750);
FORCEPROP 1 LAST VALUE 49.9
J 2
(425 1800);
DISPLAY 0.617021 (425 1800);
PAINT SKYBLUE (425 1800);
FORCEPROP 1 LASTPIN (350 1900) $PN 1
J 0
(362 1912);
DISPLAY 0.617021 (362 1912);
PAINT ORANGE (362 1912);
FORCEPROP 1 LAST TOLERANCE 1%
J 0
(450 1800);
DISPLAY 0.617021 (450 1800);
PAINT SKYBLUE (450 1800);
FORCEPROP 1 LASTPIN (550 1900) $PN 2
J 0
(512 1912);
DISPLAY 0.617021 (512 1912);
PAINT ORANGE (512 1912);
FORCEPROP 1 LAST MATERIAL CHIP
J 0
(450 1750);
DISPLAY 0.617021 (450 1750);
PAINT SKYBLUE (450 1750);
FORCEPROP 1 LAST PART_NUMBER G21796-047
J 0
(400 2000);
DISPLAY 0.617021 (400 2000);
PAINT BLUE (400 2000);
FORCEPROP 1 LAST LOCATION R6F5
J 0
(400 1950);
DISPLAY 0.617021 (400 1950);
PAINT AQUA (400 1950);
FORCEPROP 1 LAST PACK_TYPE 0402
J 0
(700 1750);
DISPLAY 0.617021 (700 1750);
PAINT SKYBLUE (700 1750);
FORCEPROP 2 LAST CDS_LIB mstr_discrete
J 0
(450 1900);
PAINT ORANGE (450 1900);
DISPLAY INVISIBLE (450 1900);
FORCEPROP 2 LAST CDS_LOCATION R6F5
J 0
(400 1950);
DISPLAY 0.617021 (400 1950);
PAINT AQUA (400 1950);
DISPLAY INVISIBLE (400 1950);
FORCEPROP 0 LAST ROOM NV_DIMM
J 0
(400 2050);
DISPLAY 1.021277 (400 2050);
PAINT ORANGE (400 2050);
DISPLAY INVISIBLE (400 2050);
FORCEPROP 1 LAST PATH I5
J 0
(400 2050);
DISPLAY 0.978723 (400 2050);
PAINT WHITE (400 2050);
DISPLAY INVISIBLE (400 2050);
FORCEPROP 0 LAST SEC 1
J 0
(400 2050);
DISPLAY 0.680851 (400 2050);
PAINT MONO (400 2050);
DISPLAY INVISIBLE (400 2050);
FORCEPROP 0 LAST BOM_COST MEM_NV
J 0
(400 2100);
DISPLAY 1.021277 (400 2100);
PAINT ORANGE (400 2100);
DISPLAY INVISIBLE (400 2100);
FORCEPROP 2 LAST SEC_TYPE 0402
J 0
(400 2100);
DISPLAY 1.021277 (400 2100);
PAINT ORANGE (400 2100);
DISPLAY INVISIBLE (400 2100);
FORCEADD RES..1
(450 1600);
FORCEPROP 1 LAST WATTAGE 1/16W
J 2
(425 1450);
DISPLAY 0.617021 (425 1450);
PAINT SKYBLUE (425 1450);
FORCEPROP 1 LAST TOLERANCE 1%
J 0
(450 1500);
DISPLAY 0.617021 (450 1500);
PAINT SKYBLUE (450 1500);
FORCEPROP 1 LAST VALUE 49.9
J 2
(425 1500);
DISPLAY 0.617021 (425 1500);
PAINT SKYBLUE (425 1500);
FORCEPROP 1 LASTPIN (350 1600) $PN 1
J 0
(362 1612);
DISPLAY 0.617021 (362 1612);
PAINT ORANGE (362 1612);
FORCEPROP 1 LASTPIN (550 1600) $PN 2
J 0
(512 1612);
DISPLAY 0.617021 (512 1612);
PAINT ORANGE (512 1612);
FORCEPROP 1 LAST MATERIAL CHIP
J 0
(450 1450);
DISPLAY 0.617021 (450 1450);
PAINT SKYBLUE (450 1450);
FORCEPROP 1 LAST PART_NUMBER G21796-047
J 0
(400 1700);
DISPLAY 0.617021 (400 1700);
PAINT BLUE (400 1700);
FORCEPROP 1 LAST LOCATION R6F2
J 0
(400 1650);
DISPLAY 0.617021 (400 1650);
PAINT AQUA (400 1650);
FORCEPROP 1 LAST PACK_TYPE 0402
J 0
(700 1450);
DISPLAY 0.617021 (700 1450);
PAINT SKYBLUE (700 1450);
FORCEPROP 2 LAST CDS_LIB mstr_discrete
J 0
(450 1600);
PAINT ORANGE (450 1600);
DISPLAY INVISIBLE (450 1600);
FORCEPROP 0 LAST SEC 1
J 0
(400 1750);
DISPLAY 0.680851 (400 1750);
PAINT MONO (400 1750);
DISPLAY INVISIBLE (400 1750);
FORCEPROP 2 LAST CDS_LOCATION R6F2
J 0
(400 1650);
DISPLAY 0.617021 (400 1650);
PAINT AQUA (400 1650);
DISPLAY INVISIBLE (400 1650);
FORCEPROP 1 LAST PATH I6
J 0
(400 1750);
DISPLAY 0.978723 (400 1750);
PAINT WHITE (400 1750);
DISPLAY INVISIBLE (400 1750);
FORCEPROP 0 LAST ROOM NV_DIMM
J 0
(400 1750);
DISPLAY 1.021277 (400 1750);
PAINT ORANGE (400 1750);
DISPLAY INVISIBLE (400 1750);
FORCEPROP 0 LAST BOM_COST MEM_NV
J 0
(400 1800);
DISPLAY 1.021277 (400 1800);
PAINT ORANGE (400 1800);
DISPLAY INVISIBLE (400 1800);
FORCEPROP 2 LAST SEC_TYPE 0402
J 0
(400 1800);
DISPLAY 1.021277 (400 1800);
PAINT ORANGE (400 1800);
DISPLAY INVISIBLE (400 1800);
FORCEADD RES..2
(-550 2700);
FORCEPROP 1 LASTPIN (-550 2600) $PN 2
J 0
(-545 2610);
DISPLAY 0.617021 (-545 2610);
PAINT ORANGE (-545 2610);
FORCEPROP 1 LASTPIN (-550 2800) $PN 1
J 0
(-545 2762);
DISPLAY 0.617021 (-545 2762);
PAINT ORANGE (-545 2762);
FORCEPROP 1 LAST PACK_TYPE 0402
J 0
(-510 2525);
DISPLAY 0.617021 (-510 2525);
PAINT SKYBLUE (-510 2525);
FORCEPROP 1 LAST VALUE 10.0K
J 0
(-505 2775);
DISPLAY 0.617021 (-505 2775);
PAINT SKYBLUE (-505 2775);
FORCEPROP 1 LAST TOLERANCE 1%
J 0
(-505 2725);
DISPLAY 0.617021 (-505 2725);
PAINT SKYBLUE (-505 2725);
FORCEPROP 1 LAST LOCATION R6F3
J 0
(-505 2825);
DISPLAY 0.617021 (-505 2825);
PAINT AQUA (-505 2825);
FORCEPROP 1 LAST PART_NUMBER G21796-016
J 0
(-510 2575);
DISPLAY 0.617021 (-510 2575);
PAINT BLUE (-510 2575);
FORCEPROP 1 LAST WATTAGE 1/16W
J 0
(-510 2675);
DISPLAY 0.617021 (-510 2675);
PAINT SKYBLUE (-510 2675);
FORCEPROP 1 LAST MATERIAL CHIP
J 0
(-510 2625);
DISPLAY 0.617021 (-510 2625);
PAINT SKYBLUE (-510 2625);
FORCEPROP 2 LAST CDS_LIB mstr_discrete
J 0
(-550 2700);
PAINT ORANGE (-550 2700);
DISPLAY INVISIBLE (-550 2700);
FORCEPROP 2 LAST CDS_LOCATION R6F3
J 0
(-505 2825);
DISPLAY 0.617021 (-505 2825);
PAINT AQUA (-505 2825);
DISPLAY INVISIBLE (-505 2825);
FORCEPROP 1 LAST PATH I7
J 0
(-500 2875);
DISPLAY 0.978723 (-500 2875);
PAINT WHITE (-500 2875);
DISPLAY INVISIBLE (-500 2875);
FORCEPROP 0 LAST ROOM NV_DIMM
J 0
(-500 2875);
DISPLAY 1.021277 (-500 2875);
PAINT ORANGE (-500 2875);
DISPLAY INVISIBLE (-500 2875);
FORCEPROP 0 LAST BOM_COST MEM_NV
J 0
(-500 2925);
DISPLAY 1.021277 (-500 2925);
PAINT ORANGE (-500 2925);
DISPLAY INVISIBLE (-500 2925);
FORCEPROP 2 LAST SEC_TYPE 0402
J 0
(-500 2925);
DISPLAY 1.021277 (-500 2925);
PAINT ORANGE (-500 2925);
DISPLAY INVISIBLE (-500 2925);
FORCEPROP 0 LAST SEC 1
J 0
(-500 2875);
DISPLAY 0.680851 (-500 2875);
PAINT MONO (-500 2875);
DISPLAY INVISIBLE (-500 2875);
FORCEADD OFFPAGE..1
(-2650 2400);
FORCEPROP 2 LAST $XR0 120 
J 0
(-2902 2400);
DISPLAY 0.638298 (-2902 2400);
PAINT MONO (-2902 2400);
FORCEPROP 2 LAST $XR1 191 
J 0
(-3022 2400);
DISPLAY 0.638298 (-3022 2400);
PAINT MONO (-3022 2400);
FORCEPROP 2 LASTPIN (-2600 2400) SIG_NAME FM_ADR_COMPLETE
J 0
(-2610 2410);
DISPLAY 0.617021 (-2610 2410);
PAINT ORANGE (-2610 2410);
FORCEPROP 2 LAST PATH I9
J 0
(-2600 2475);
DISPLAY 1.021277 (-2600 2475);
PAINT ORANGE (-2600 2475);
DISPLAY INVISIBLE (-2600 2475);
FORCEPROP 2 LAST CDS_LIB mstr_standard
J 0
(-2650 2400);
PAINT ORANGE (-2650 2400);
DISPLAY INVISIBLE (-2650 2400);
FORCEPROP 1 LAST COMMENT_BODY TRUE
J 0
(-2525 2300);
DISPLAY 0.872340 (-2525 2300);
PAINT GREEN (-2525 2300);
DISPLAY INVISIBLE (-2525 2300);
FORCEPROP 1 LAST OFFPAGE TRUE
J 0
(-2325 2275);
DISPLAY 0.872340 (-2325 2275);
PAINT GREEN (-2325 2275);
DISPLAY INVISIBLE (-2325 2275);
FORCEADD DNS..2
(-1645 2395);
PAINT RED (-1645 2395);
FORCEPROP 1 LAST COMMENT_BODY TRUE
R 1
J 0
(-1570 2170);
DISPLAY 0.872340 (-1570 2170);
PAINT GREEN (-1570 2170);
DISPLAY INVISIBLE (-1570 2170);
FORCEPROP 2 LAST CDS_LIB mstr_misc
J 0
(-1645 2395);
PAINT ORANGE (-1645 2395);
DISPLAY INVISIBLE (-1645 2395);
FORCEADD DNS..2
(3330 2895);
PAINT RED (3330 2895);
FORCEPROP 1 LAST COMMENT_BODY TRUE
R 1
J 0
(3405 2670);
DISPLAY 0.872340 (3405 2670);
PAINT GREEN (3405 2670);
DISPLAY INVISIBLE (3405 2670);
FORCEPROP 2 LAST CDS_LIB mstr_misc
J 0
(3330 2895);
PAINT ORANGE (3330 2895);
DISPLAY INVISIBLE (3330 2895);
FORCEADD INTEL_CORP_BPAGE..1
(4700 200);
FORCEPROP 1 LAST CDS_CON_LAST_MODIFIED Tue Dec 01 11:51:47 2015
J 0
(3275 525);
PAINT ORANGE (3275 525);
DISPLAY INVISIBLE (3275 525);
FORCEPROP 1 LAST CUSTOM_TXT_CDS <CURRENT_DESIGN_SHEET> OF <TOTAL_DESIGN_SHEETS>
J 0
(4200 225);
PAINT GREEN (4200 225);
FORCEPROP 1 LAST CUSTOM_TXT_CDS <CON_LAST_MODIFIED>
J 0
(2775 550);
PAINT GREEN (2775 550);
FORCEPROP 2 LAST CUSTOM_TXT_CDS <XR_PAGE_TITLE>
J 0
(-3190 5450);
DISPLAY 0.638298 (-3190 5450);
PAINT PINK (-3190 5450);
DISPLAY INVISIBLE (-3190 5450);
FORCEPROP 1 LAST SCH_TITLE NVDIMM SUPPORT
J 0
(-3250 250);
DISPLAY 1.212766 (-3250 250);
PAINT ORANGE (-3250 250);
FORCEPROP 1 LAST SCH_ADDRESS1 2200 Mission College Blvd.
J 0
(725 325);
DISPLAY 0.617021 (725 325);
PAINT GREEN (725 325);
FORCEPROP 1 LAST SCH_ADDRESS2 P.O. BOX 58119
J 0
(725 275);
DISPLAY 0.617021 (725 275);
PAINT GREEN (725 275);
FORCEPROP 1 LAST SCH_ADDRESS3 Santa Clara, CA 95052-8119
J 0
(725 225);
DISPLAY 0.617021 (725 225);
PAINT GREEN (725 225);
FORCEPROP 1 LAST SCH_NUMBER H4694802
J 0
(3400 350);
DISPLAY 1.212766 (3400 350);
PAINT YELLOW (3400 350);
FORCEPROP 1 LAST SCH_DEPT BESD
J 1
(250 300);
DISPLAY 1.212766 (250 300);
PAINT YELLOW (250 300);
FORCEPROP 1 LAST SCH_REV 2.420
J 0
(4450 350);
DISPLAY 0.978723 (4450 350);
PAINT YELLOW (4450 350);
FORCEPROP 2 LAST PAGE_BORDER TRUE
J 0
(-3190 5450);
DISPLAY 0.638298 (-3190 5450);
PAINT PINK (-3190 5450);
DISPLAY INVISIBLE (-3190 5450);
FORCEPROP 1 LAST COMMENT_BODY TRUE
J 0
(4712 212);
DISPLAY 0.468085 (4712 212);
PAINT GREEN (4712 212);
DISPLAY INVISIBLE (4712 212);
FORCEPROP 2 LAST CDS_LIB mstr_symbols
J 0
(4700 200);
PAINT MONO (4700 200);
DISPLAY INVISIBLE (4700 200);
FORCEPROP 2 LAST CDS_XR_PAGE_TITLE CR-89 : @BASEBOARD_FAB2_LIB.BASEBOARD_FAB2(SCH_1):PAGE89
J 0
(-3190 5450);
DISPLAY 0.638298 (-3190 5450);
PAINT PINK (-3190 5450);
DISPLAY INVISIBLE (-3190 5450);
WIRE 16 -1 (-550 2000)(-550 1950);
WIRE 16 -1 (-550 2800)(-550 2900);
WIRE 16 -1 (1850 3975)(1850 4050);
WIRE 16 -1 (2550 4200)(2550 4275);
WIRE 16 -1 (2550 3450)(2550 3375);
WIRE 16 -1 (1850 2975)(1850 2900);
WIRE 16 -1 (3425 2900)(3950 2900);
FORCEPROP 2 LAST SIG_NAME FM_ADR_SMI_GPIO_N
J 2
(3925 2935);
DISPLAY 0.617021 (3925 2935);
PAINT ORANGE (3925 2935);
WIRE 16 -1 (3050 2900)(3225 2900);
WIRE 16 -1 (3050 2900)(3050 3925);
WIRE 16 -1 (3050 3925)(3550 3925);
WIRE 16 -1 (2550 3925)(3050 3925);
FORCEPROP 2 LAST SIG_NAME IRQ_DIMM_SAVE_LVT3_N
J 0
(2865 3960);
DISPLAY 0.617021 (2865 3960);
PAINT ORANGE (2865 3960);
WIRE 16 -1 (2550 3925)(2550 4000);
WIRE 16 -1 (2550 3650)(2550 3925);
WIRE 16 -1 (1850 3550)(2400 3550);
WIRE 16 -1 (1850 3550)(1850 3775);
WIRE 16 -1 (1850 3175)(1850 3550);
FORCEPROP 2 LAST SIG_NAME IRQ_DIMM_SAVE_LVT3
J 0
(1865 3585);
DISPLAY 0.617021 (1865 3585);
PAINT ORANGE (1865 3585);
FORCEPROP 2 LASTPROP $XRERR UNIQUE?
J 0
(1625 3585);
DISPLAY 0.638298 (1625 3585);
PAINT MONO (1625 3585);
DISPLAY INVISIBLE (1625 3585);
WIRE 16 -1 (1700 3075)(975 3075);
FORCEPROP 2 LAST SIG_NAME IRQ_DIMM_SAVE_R_N
J 0
(1115 3085);
DISPLAY 0.617021 (1115 3085);
PAINT ORANGE (1115 3085);
FORCEPROP 2 LASTPROP $XRERR UNIQUE?
J 0
(875 3085);
DISPLAY 0.638298 (875 3085);
PAINT MONO (875 3085);
DISPLAY INVISIBLE (875 3085);
WIRE 16 -1 (550 2500)(1450 2500);
WIRE 16 -1 (550 2200)(1450 2200);
WIRE 16 -1 (350 1600)(100 1600);
WIRE 16 -1 (100 1600)(100 1900);
WIRE 16 -1 (100 1900)(100 2200);
WIRE 16 -1 (100 1900)(350 1900);
WIRE 16 -1 (100 2200)(350 2200);
WIRE 16 -1 (100 2200)(100 2500);
WIRE 16 -1 (100 2500)(350 2500);
WIRE 16 -1 (-25 2500)(100 2500);
WIRE 16 -1 (-25 2500)(-25 3075);
WIRE 16 -1 (-550 2500)(-25 2500);
WIRE 16 -1 (-550 2600)(-550 2500);
WIRE 16 -1 (-550 2500)(-550 2400);
WIRE 16 -1 (-25 3075)(775 3075);
FORCEPROP 2 LAST SIG_NAME IRQ_DIMM_SAVE_N
J 0
(215 3085);
DISPLAY 0.617021 (215 3085);
PAINT ORANGE (215 3085);
FORCEPROP 2 LASTPROP $XRERR UNIQUE?
J 0
(-25 3085);
DISPLAY 0.638298 (-25 3085);
PAINT MONO (-25 3085);
DISPLAY INVISIBLE (-25 3085);
WIRE 16 -1 (550 1900)(1450 1900);
WIRE 16 -1 (1450 1600)(550 1600);
WIRE 16 -1 (-750 2100)(-1150 2100);
WIRE 16 -1 (-1150 2400)(-1150 2100);
WIRE 16 -1 (-1550 2100)(-1150 2100);
FORCEPROP 2 LAST SIG_NAME FM_ADR_COMPLETE_R
J 0
(-1360 2110);
DISPLAY 0.617021 (-1360 2110);
PAINT ORANGE (-1360 2110);
FORCEPROP 2 LASTPROP $XRERR UNIQUE?
J 0
(-1600 2110);
DISPLAY 0.638298 (-1600 2110);
PAINT MONO (-1600 2110);
DISPLAY INVISIBLE (-1600 2110);
WIRE 16 -1 (-1550 2400)(-1150 2400);
WIRE 16 -1 (-2600 2100)(-1750 2100);
WIRE 16 -1 (-2600 2400)(-1750 2400);
DOT 1 (3050 3925);
DOT 1 (2550 3925);
DOT 1 (1850 3550);
DOT 1 (100 2200);
DOT 1 (100 2500);
DOT 1 (100 1900);
DOT 1 (-25 2500);
DOT 1 (-550 2500);
DOT 1 (-1150 2100);
FORCENOTE
NVDIMM INTERNAL R-PULLUP TO VPP (2.5V) IS 2 K OHM TO SUPPORT UP TO 6 NVDIMM LOADS TOTAL ON ALL FM_ADR_COMPLETE_XXX_N NETS
(-2400 1200) 0;
DISPLAY LEFT (-2400 1200);
DISPLAY 1.021277 (-2400 1200);
PAINT PURPLE (-2400 1200);
FORCENOTE
IMPORTANT DESIGN NOTE:
(-2400 1300) 0;
DISPLAY LEFT (-2400 1300);
DISPLAY 1.021277 (-2400 1300);
PAINT PURPLE (-2400 1300);
FORCENOTE
BOM_COST=MEM_NV
(-3250 375) 0;
DISPLAY LEFT (-3250 375);
DISPLAY 1.021277 (-3250 375);
PAINT PURPLE (-3250 375);
FORCENOTE
ROOM=NVDIMM
(-3200 450) 0;
DISPLAY LEFT (-3200 450);
DISPLAY 1.021277 (-3200 450);
PAINT PURPLE (-3200 450);
QUIT
